(kicad_pcb
	(version 20260206)
	(generator "pcbnew")
	(generator_version "10.0")
	(general
		(thickness 1.6)
		(legacy_teardrops no)
	)
	(paper "A4")
	(title_block
		(title "peb — Lightning_PEB_BRD.brd")
		(comment 1 "Lightning (Wiwynn / Facebook NVMe JBOF) / footprints 1189-1195 of 2563")
	)
	(layers
		(0 "F.Cu" signal "TOP")
		(4 "In1.Cu" signal "L2GND")
		(6 "In2.Cu" signal "L3")
		(8 "In3.Cu" signal "L4VCC")
		(10 "In4.Cu" signal "L5VCC")
		(12 "In5.Cu" signal "L6")
		(14 "In6.Cu" signal "L7GND")
		(2 "B.Cu" signal "BOTTOM")
		(9 "F.Adhes" user "F.Adhesive")
		(11 "B.Adhes" user "B.Adhesive")
		(13 "F.Paste" user "Package Geometry/Pastemask Top")
		(15 "B.Paste" user "Package Geometry/Pastemask Bottom")
		(5 "F.SilkS" user "Ref Des/Silkscreen Top")
		(7 "B.SilkS" user "Ref Des/Silkscreen Bottom")
		(1 "F.Mask" user "Board Geometry/Soldermask Top")
		(3 "B.Mask" user "Board Geometry/Soldermask Bottom")
		(17 "Dwgs.User" user "User.Drawings")
		(19 "Cmts.User" user "User.Comments")
		(21 "Eco1.User" user "User.Eco1")
		(23 "Eco2.User" user "User.Eco2")
		(25 "Edge.Cuts" user "Board Geometry/Outline")
		(27 "Margin" user)
		(31 "F.CrtYd" user "Package Geometry/Place Bound Top")
		(29 "B.CrtYd" user "Package Geometry/Place Bound Bottom")
		(35 "F.Fab" user "Ref Des/Assembly Top")
		(33 "B.Fab" user "Ref Des/Assembly Bottom")
	)
	(footprint ""
		(layer "F.Cu")
		(at 51.181 -181.483 90)
		(property "Reference" "U33"
			(at 0 0 90)
			(layer "F.SilkS")
			(hide yes)
			(effects
				(font
					(size 1.27 1.27)
				)
			)
		)
		(property "Value" "PCA9511ADP-T-GP"
			(at 0 -13.1572 90)
			(unlocked yes)
			(layer "F.Fab")
			(hide yes)
			(effects
				(font
					(size 1.016 1.016)
					(thickness 0.1524)
				)
			)
		)
		(property "Device Type" "SSOIC8-2H44"
			(at 0 -15.1892 90)
			(unlocked yes)
			(layer "F.Fab")
			(hide yes)
			(effects
				(font
					(size 1.016 1.016)
					(thickness 0.1524)
				)
			)
		)
		(duplicate_pad_numbers_are_jumpers no)
		(fp_line
			(start 1.0922 -1.016)
			(end 1.0922 1.016)
			(stroke
				(width 0.1524)
				(type default)
			)
			(layer "F.SilkS")
		)
		(fp_line
			(start -1.9304 -1.016)
			(end 1.0922 -1.016)
			(stroke
				(width 0.1524)
				(type default)
			)
			(layer "F.SilkS")
		)
		(fp_line
			(start -1.524 0)
			(end -1.9304 -0.4064)
			(stroke
				(width 0.1524)
				(type default)
			)
			(layer "F.SilkS")
		)
		(fp_line
			(start -1.524 0)
			(end -1.9304 0.4064)
			(stroke
				(width 0.1524)
				(type default)
			)
			(layer "F.SilkS")
		)
		(fp_line
			(start 1.0922 1.016)
			(end -1.9304 1.016)
			(stroke
				(width 0.1524)
				(type default)
			)
			(layer "F.SilkS")
		)
		(fp_line
			(start -1.9304 1.016)
			(end -1.9304 -1.016)
			(stroke
				(width 0.1524)
				(type default)
			)
			(layer "F.SilkS")
		)
		(fp_line
			(start -1.7018 1.0414)
			(end -1.7018 2.9718)
			(stroke
				(width 0.635)
				(type default)
			)
			(layer "F.SilkS")
		)
		(fp_poly
			(pts
				(xy -1.1938 -1.016) (xy 1.0922 -1.016) (xy 1.0922 1.016) (xy -1.1938 1.016)
			)
			(stroke
				(width 0)
				(type default)
			)
			(fill yes)
			(layer "F.SilkS")
		)
		(fp_rect
			(start -2.0066 3.3401)
			(end 2.0066 -3.3401)
			(stroke
				(width 0)
				(type default)
			)
			(fill no)
			(layer "F.CrtYd")
		)
		(fp_poly
			(pts
				(xy -2.0066 -3.3401) (xy 2.0066 -3.3401) (xy 2.0066 3.3401) (xy -2.0066 3.3401)
			)
			(stroke
				(width 0)
				(type default)
			)
			(fill no)
			(layer "F.Fab")
		)
		(pad "1" smd rect
			(at -0.97536 2.0701 90)
			(size 0.4064 1.524)
			(layers "F.Cu" "F.Mask" "F.Paste")
			(net "I2C8_BUFF_EN")
		)
		(pad "2" smd rect
			(at -0.32512 2.0701 90)
			(size 0.4064 1.524)
			(layers "F.Cu" "F.Mask" "F.Paste")
			(net "BMC_I2C8_CLKBUF1_SCL_R")
		)
		(pad "3" smd rect
			(at 0.32512 2.0701 90)
			(size 0.4064 1.524)
			(layers "F.Cu" "F.Mask" "F.Paste")
			(net "BUF_I2C8_CLKBUF1_SCL_R")
		)
		(pad "4" smd rect
			(at 0.97536 2.0701 90)
			(size 0.4064 1.524)
			(layers "F.Cu" "F.Mask" "F.Paste")
			(net "GND")
		)
		(pad "5" smd rect
			(at 0.97536 -2.0701 90)
			(size 0.4064 1.524)
			(layers "F.Cu" "F.Mask" "F.Paste")
			(net "I2C8_BUF_READY")
		)
		(pad "6" smd rect
			(at 0.32512 -2.0701 90)
			(size 0.4064 1.524)
			(layers "F.Cu" "F.Mask" "F.Paste")
			(net "BUF_I2C8_CLKBUF1_SDA_R")
		)
		(pad "7" smd rect
			(at -0.32512 -2.0701 90)
			(size 0.4064 1.524)
			(layers "F.Cu" "F.Mask" "F.Paste")
			(net "BMC_I2C8_CLKBUF1_SDA_R")
		)
		(pad "8" smd rect
			(at -0.97536 -2.0701 90)
			(size 0.4064 1.524)
			(layers "F.Cu" "F.Mask" "F.Paste")
			(net "P3V3_STBY")
		)
	)
	(footprint ""
		(layer "F.Cu")
		(at 12.6365 -50.8254 -90)
		(property "Reference" "D12"
			(at 0 0 270)
			(layer "F.SilkS")
			(hide yes)
			(effects
				(font
					(size 1.27 1.27)
				)
			)
		)
		(property "Value" "PGB1010603MR-GP"
			(at -0.0254 -2.8956 270)
			(unlocked yes)
			(layer "F.Fab")
			(hide yes)
			(effects
				(font
					(size 1.016 1.016)
					(thickness 0.1524)
				)
			)
		)
		(property "Device Type" "L1608-UH15"
			(at -0.0254 -4.4196 270)
			(unlocked yes)
			(layer "F.Fab")
			(hide yes)
			(effects
				(font
					(size 1.016 1.016)
					(thickness 0.1524)
				)
			)
		)
		(duplicate_pad_numbers_are_jumpers no)
		(fp_line
			(start 0.254 0)
			(end -0.254 0)
			(stroke
				(width 0.2032)
				(type default)
			)
			(layer "F.SilkS")
		)
		(fp_rect
			(start -0.5842 1.3335)
			(end 0.5842 -1.3335)
			(stroke
				(width 0)
				(type default)
			)
			(fill no)
			(layer "F.CrtYd")
		)
		(fp_rect
			(start -0.5842 1.3335)
			(end 0.5842 -1.3335)
			(stroke
				(width 0)
				(type default)
			)
			(fill no)
			(layer "F.Fab")
		)
		(pad "1" smd custom
			(at 0 -0.762 270)
			(size 0.2159 0.2159)
			(layers "F.Cu" "F.Mask" "F.Paste")
			(net "NIC0_MDI0_N1_R")
			(options
				(clearance outline)
				(anchor circle)
			)
			(primitives
				(gr_poly
					(pts
						(arc
							(start -0.3302 -0.4318)
							(mid -0.402042 -0.402042)
							(end -0.4318 -0.3302)
						)
						(arc
							(start -0.4318 0.3302)
							(mid -0.402042 0.402042)
							(end -0.3302 0.4318)
						)
						(arc
							(start 0.3302 0.4318)
							(mid 0.402042 0.402042)
							(end 0.4318 0.3302)
						)
						(arc
							(start 0.4318 -0.3302)
							(mid 0.402042 -0.402042)
							(end 0.3302 -0.4318)
						)
					)
					(width 0)
					(fill yes)
				)
			)
		)
		(pad "2" smd custom
			(at 0 0.762 270)
			(size 0.2159 0.2159)
			(layers "F.Cu" "F.Mask" "F.Paste")
			(net "GND")
			(options
				(clearance outline)
				(anchor circle)
			)
			(primitives
				(gr_poly
					(pts
						(arc
							(start -0.3302 -0.4318)
							(mid -0.402042 -0.402042)
							(end -0.4318 -0.3302)
						)
						(arc
							(start -0.4318 0.3302)
							(mid -0.402042 0.402042)
							(end -0.3302 0.4318)
						)
						(arc
							(start 0.3302 0.4318)
							(mid 0.402042 0.402042)
							(end 0.4318 0.3302)
						)
						(arc
							(start 0.4318 -0.3302)
							(mid 0.402042 -0.402042)
							(end 0.3302 -0.4318)
						)
					)
					(width 0)
					(fill yes)
				)
			)
		)
	)
	(footprint ""
		(layer "F.Cu")
		(at 157.318202 -58.447432 180)
		(property "Reference" "PC204"
			(at 0 0 180)
			(layer "F.SilkS")
			(hide yes)
			(effects
				(font
					(size 1.27 1.27)
				)
			)
		)
		(property "Value" "SC1U10V2KX-1GP"
			(at 1.1811 -2.7051 180)
			(unlocked yes)
			(layer "F.Fab")
			(hide yes)
			(effects
				(font
					(size 1.016 1.016)
					(thickness 0.1524)
				)
			)
		)
		(property "Device Type" "C402H22"
			(at 1.1811 -4.2291 180)
			(unlocked yes)
			(layer "F.Fab")
			(hide yes)
			(effects
				(font
					(size 1.016 1.016)
					(thickness 0.1524)
				)
			)
		)
		(duplicate_pad_numbers_are_jumpers no)
		(fp_rect
			(start -0.4318 0.9525)
			(end 0.4318 -0.9525)
			(stroke
				(width 0)
				(type default)
			)
			(fill no)
			(layer "F.CrtYd")
		)
		(fp_rect
			(start -0.4318 0.9525)
			(end 0.4318 -0.9525)
			(stroke
				(width 0)
				(type default)
			)
			(fill no)
			(layer "F.Fab")
		)
		(pad "1" smd custom
			(at 0 -0.4445 180)
			(size 0.1524 0.1524)
			(layers "F.Cu" "F.Mask" "F.Paste")
			(net "GND")
			(options
				(clearance outline)
				(anchor circle)
			)
			(primitives
				(gr_poly
					(pts
						(arc
							(start 0.3048 -0.2032)
							(mid 0.275042 -0.275042)
							(end 0.2032 -0.3048)
						)
						(arc
							(start -0.2032 -0.3048)
							(mid -0.275042 -0.275042)
							(end -0.3048 -0.2032)
						)
						(arc
							(start -0.3048 0.2032)
							(mid -0.275042 0.275042)
							(end -0.2032 0.3048)
						)
						(arc
							(start 0.2032 0.3048)
							(mid 0.275042 0.275042)
							(end 0.3048 0.2032)
						)
					)
					(width 0)
					(fill yes)
				)
			)
		)
		(pad "2" smd custom
			(at 0 0.4445 180)
			(size 0.1524 0.1524)
			(layers "F.Cu" "F.Mask" "F.Paste")
			(net "P0V9_EN")
			(options
				(clearance outline)
				(anchor circle)
			)
			(primitives
				(gr_poly
					(pts
						(arc
							(start 0.3048 -0.2032)
							(mid 0.275042 -0.275042)
							(end 0.2032 -0.3048)
						)
						(arc
							(start -0.2032 -0.3048)
							(mid -0.275042 -0.275042)
							(end -0.3048 -0.2032)
						)
						(arc
							(start -0.3048 0.2032)
							(mid -0.275042 0.275042)
							(end -0.2032 0.3048)
						)
						(arc
							(start 0.2032 0.3048)
							(mid 0.275042 0.275042)
							(end 0.3048 0.2032)
						)
					)
					(width 0)
					(fill yes)
				)
			)
		)
	)
	(footprint ""
		(layer "F.Cu")
		(at 313.563 -54.483)
		(property "Reference" "PTC5"
			(at 0 0 0)
			(layer "F.SilkS")
			(hide yes)
			(effects
				(font
					(size 1.27 1.27)
				)
			)
		)
		(property "Value" "SE470UF2VDM-GP"
			(at 0 -9.6012 0)
			(unlocked yes)
			(layer "F.Fab")
			(hide yes)
			(effects
				(font
					(size 1.016 1.016)
					(thickness 0.1524)
				)
			)
		)
		(property "Device Type" "CT7343H83"
			(at 0 -11.1252 0)
			(unlocked yes)
			(layer "F.Fab")
			(hide yes)
			(effects
				(font
					(size 1.016 1.016)
					(thickness 0.1524)
				)
			)
		)
		(duplicate_pad_numbers_are_jumpers no)
		(fp_line
			(start -2.286 -4.8768)
			(end -2.286 -2.032)
			(stroke
				(width 0.1524)
				(type default)
			)
			(layer "F.SilkS")
		)
		(fp_line
			(start -2.286 4.8768)
			(end -2.286 2.032)
			(stroke
				(width 0.1524)
				(type default)
			)
			(layer "F.SilkS")
		)
		(fp_line
			(start 2.1082 -4.699)
			(end -2.1082 -4.699)
			(stroke
				(width 0.508)
				(type default)
			)
			(layer "F.SilkS")
		)
		(fp_line
			(start 2.286 -4.8768)
			(end -2.286 -4.8768)
			(stroke
				(width 0.1524)
				(type default)
			)
			(layer "F.SilkS")
		)
		(fp_line
			(start 2.286 -2.032)
			(end 2.286 -4.8768)
			(stroke
				(width 0.1524)
				(type default)
			)
			(layer "F.SilkS")
		)
		(fp_line
			(start 2.286 2.032)
			(end 2.286 4.8768)
			(stroke
				(width 0.1524)
				(type default)
			)
			(layer "F.SilkS")
		)
		(fp_line
			(start 2.286 4.8768)
			(end -2.286 4.8768)
			(stroke
				(width 0.1524)
				(type default)
			)
			(layer "F.SilkS")
		)
		(fp_rect
			(start -2.1463 3.6449)
			(end 2.1463 -3.6449)
			(stroke
				(width 0)
				(type default)
			)
			(fill no)
			(layer "F.CrtYd")
		)
		(fp_poly
			(pts
				(xy -2.54 4.953) (xy -2.54 4.2926) (xy -3.81 4.2926) (xy -3.81 -4.2926) (xy -2.54 -4.2926) (xy -2.54 -4.953)
				(xy 2.54 -4.953) (xy 2.54 -4.2926) (xy 3.81 -4.2926) (xy 3.81 -1.6256) (xy 2.1463 -1.6256) (xy 2.1463 -3.6449)
				(xy -2.1463 -3.6449) (xy -2.1463 3.6449) (xy 2.1463 3.6449) (xy 2.1463 -1.6129) (xy 3.81 -1.6129)
				(xy 3.81 4.2926) (xy 2.54 4.2926) (xy 2.54 4.953)
			)
			(stroke
				(width 0)
				(type default)
			)
			(fill no)
			(layer "F.CrtYd")
		)
		(fp_rect
			(start -3.81 4.2926)
			(end -2.54 -4.2926)
			(stroke
				(width 0)
				(type default)
			)
			(fill no)
			(layer "F.Fab")
		)
		(fp_rect
			(start -2.54 4.953)
			(end 2.54 -4.953)
			(stroke
				(width 0)
				(type default)
			)
			(fill no)
			(layer "F.Fab")
		)
		(fp_rect
			(start 2.54 4.2926)
			(end 3.81 -4.2926)
			(stroke
				(width 0)
				(type default)
			)
			(fill no)
			(layer "F.Fab")
		)
		(pad "1" smd rect
			(at 0 -3.1496)
			(size 2.413 2.286)
			(layers "F.Cu" "F.Mask" "F.Paste")
			(net "P0V9_E")
		)
		(pad "2" smd rect
			(at 0 3.1496)
			(size 2.413 2.286)
			(layers "F.Cu" "F.Mask" "F.Paste")
			(net "GND")
		)
		(zone
			(layer "F.Cu")
			(hatch none 0.5)
			(connect_pads
				(clearance 0)
			)
			(min_thickness 0.25)
			(keepout
				(tracks allowed)
				(vias not_allowed)
				(pads allowed)
				(copperpour not_allowed)
				(footprints allowed)
			)
			(placement
				(enabled no)
				(sheetname "")
			)
			(fill
				(thermal_gap 0.5)
				(thermal_bridge_width 0.5)
				(island_removal_mode 0)
			)
			(polygon
				(pts
					(xy 312.0517 -49.8856) (xy 315.0743 -49.8856) (xy 315.0743 -52.7812) (xy 315.0743 -53.1114) (xy 312.0517 -53.1114)
					(xy 312.0517 -52.7812)
				)
			)
		)
		(zone
			(layer "F.Cu")
			(hatch none 0.5)
			(connect_pads
				(clearance 0)
			)
			(min_thickness 0.25)
			(keepout
				(tracks allowed)
				(vias not_allowed)
				(pads allowed)
				(copperpour not_allowed)
				(footprints allowed)
			)
			(placement
				(enabled no)
				(sheetname "")
			)
			(fill
				(thermal_gap 0.5)
				(thermal_bridge_width 0.5)
				(island_removal_mode 0)
			)
			(polygon
				(pts
					(xy 315.0743 -56.1721) (xy 315.0743 -59.0804) (xy 312.0517 -59.0804) (xy 312.0517 -56.1848) (xy 312.0517 -55.8546)
					(xy 315.0743 -55.8546)
				)
			)
		)
	)
	(footprint ""
		(layer "F.Cu")
		(at 310.007 -61.6966)
		(property "Reference" "PG45"
			(at 0 0 0)
			(layer "F.SilkS")
			(hide yes)
			(effects
				(font
					(size 1.27 1.27)
				)
			)
		)
		(property "Value" "GAP-CLOSE-PWR-3-GP"
			(at 0.0254 -6.5786 0)
			(unlocked yes)
			(layer "F.Fab")
			(hide yes)
			(effects
				(font
					(size 1.016 1.016)
					(thickness 0.1524)
				)
			)
		)
		(property "Device Type" "GAP-CLOSE-PWR-3"
			(at 0.0254 -8.255 0)
			(unlocked yes)
			(layer "F.Fab")
			(hide yes)
			(effects
				(font
					(size 1.016 1.016)
					(thickness 0.1524)
				)
			)
		)
		(duplicate_pad_numbers_are_jumpers no)
		(fp_rect
			(start -0.7112 0.4572)
			(end 0.7112 -0.4572)
			(stroke
				(width 0)
				(type default)
			)
			(fill no)
			(layer "F.CrtYd")
		)
		(fp_poly
			(pts
				(xy -0.7112 -0.4572) (xy 0.7112 -0.4572) (xy 0.7112 0.4572) (xy -0.7112 0.4572)
			)
			(stroke
				(width 0)
				(type default)
			)
			(fill no)
			(layer "F.Fab")
		)
		(pad "1" smd rect
			(at -0.3048 0)
			(size 0.6604 0.762)
			(layers "F.Cu" "F.Mask" "F.Paste")
			(net "DUT_VDD")
		)
		(pad "2" smd rect
			(at 0.3048 0)
			(size 0.6604 0.762)
			(layers "F.Cu" "F.Mask" "F.Paste")
			(net "P0V9_E")
		)
	)
	(footprint ""
		(layer "F.Cu")
		(at 8.001 -55.5498 180)
		(property "Reference" "C421"
			(at 0 0 180)
			(layer "F.SilkS")
			(hide yes)
			(effects
				(font
					(size 1.27 1.27)
				)
			)
		)
		(property "Value" "SCD1U16V2KX-3GP"
			(at 1.1811 -2.7051 180)
			(unlocked yes)
			(layer "F.Fab")
			(hide yes)
			(effects
				(font
					(size 1.016 1.016)
					(thickness 0.1524)
				)
			)
		)
		(property "Device Type" "C402H22"
			(at 1.1811 -4.2291 180)
			(unlocked yes)
			(layer "F.Fab")
			(hide yes)
			(effects
				(font
					(size 1.016 1.016)
					(thickness 0.1524)
				)
			)
		)
		(duplicate_pad_numbers_are_jumpers no)
		(fp_rect
			(start -0.4318 0.9525)
			(end 0.4318 -0.9525)
			(stroke
				(width 0)
				(type default)
			)
			(fill no)
			(layer "F.CrtYd")
		)
		(fp_rect
			(start -0.4318 0.9525)
			(end 0.4318 -0.9525)
			(stroke
				(width 0)
				(type default)
			)
			(fill no)
			(layer "F.Fab")
		)
		(pad "1" smd custom
			(at 0 -0.4445 180)
			(size 0.1524 0.1524)
			(layers "F.Cu" "F.Mask" "F.Paste")
			(net "LED_MDI0_LINK_N")
			(options
				(clearance outline)
				(anchor circle)
			)
			(primitives
				(gr_poly
					(pts
						(arc
							(start 0.3048 -0.2032)
							(mid 0.275042 -0.275042)
							(end 0.2032 -0.3048)
						)
						(arc
							(start -0.2032 -0.3048)
							(mid -0.275042 -0.275042)
							(end -0.3048 -0.2032)
						)
						(arc
							(start -0.3048 0.2032)
							(mid -0.275042 0.275042)
							(end -0.2032 0.3048)
						)
						(arc
							(start 0.2032 0.3048)
							(mid 0.275042 0.275042)
							(end 0.3048 0.2032)
						)
					)
					(width 0)
					(fill yes)
				)
			)
		)
		(pad "2" smd custom
			(at 0 0.4445 180)
			(size 0.1524 0.1524)
			(layers "F.Cu" "F.Mask" "F.Paste")
			(net "GND")
			(options
				(clearance outline)
				(anchor circle)
			)
			(primitives
				(gr_poly
					(pts
						(arc
							(start 0.3048 -0.2032)
							(mid 0.275042 -0.275042)
							(end 0.2032 -0.3048)
						)
						(arc
							(start -0.2032 -0.3048)
							(mid -0.275042 -0.275042)
							(end -0.3048 -0.2032)
						)
						(arc
							(start -0.3048 0.2032)
							(mid -0.275042 0.275042)
							(end -0.2032 0.3048)
						)
						(arc
							(start 0.2032 0.3048)
							(mid 0.275042 0.275042)
							(end 0.3048 0.2032)
						)
					)
					(width 0)
					(fill yes)
				)
			)
		)
	)
	(footprint ""
		(layer "F.Cu")
		(at 119.4308 -17.0688 180)
		(property "Reference" "R752"
			(at 0 0 180)
			(layer "F.SilkS")
			(hide yes)
			(effects
				(font
					(size 1.27 1.27)
				)
			)
		)
		(property "Value" "4K7R2F-GP"
			(at 0.064008 -3.993896 180)
			(unlocked yes)
			(layer "F.Fab")
			(hide yes)
			(effects
				(font
					(size 1.016 1.016)
					(thickness 0.1524)
				)
			)
		)
		(property "Device Type" "R402H16"
			(at 0.064008 -5.517896 180)
			(unlocked yes)
			(layer "F.Fab")
			(hide yes)
			(effects
				(font
					(size 1.016 1.016)
					(thickness 0.1524)
				)
			)
		)
		(duplicate_pad_numbers_are_jumpers no)
		(fp_line
			(start 0.508 -0.9398)
			(end -0.508 -0.9398)
			(stroke
				(width 0.1524)
				(type default)
			)
			(layer "F.SilkS")
		)
		(fp_line
			(start -0.508 -0.9398)
			(end -0.508 0.9398)
			(stroke
				(width 0.1524)
				(type default)
			)
			(layer "F.SilkS")
		)
		(fp_rect
			(start -0.508 0.9398)
			(end 0.508 -0.9398)
			(stroke
				(width 0)
				(type default)
			)
			(fill no)
			(layer "F.CrtYd")
		)
		(fp_rect
			(start -0.508 0.9398)
			(end 0.508 -0.9398)
			(stroke
				(width 0)
				(type default)
			)
			(fill no)
			(layer "F.Fab")
		)
		(pad "1" smd custom
			(at 0 -0.4445 180)
			(size 0.1397 0.1397)
			(layers "F.Cu" "F.Mask" "F.Paste")
			(net "GND")
			(options
				(clearance outline)
				(anchor circle)
			)
			(primitives
				(gr_poly
					(pts
						(arc
							(start -0.1778 -0.2794)
							(mid -0.249642 -0.249642)
							(end -0.2794 -0.1778)
						)
						(arc
							(start -0.2794 0.1778)
							(mid -0.249642 0.249642)
							(end -0.1778 0.2794)
						)
						(arc
							(start 0.1778 0.2794)
							(mid 0.249642 0.249642)
							(end 0.2794 0.1778)
						)
						(arc
							(start 0.2794 -0.1778)
							(mid 0.249642 -0.249642)
							(end 0.1778 -0.2794)
						)
					)
					(width 0)
					(fill yes)
				)
			)
		)
		(pad "2" smd custom
			(at 0 0.4445 180)
			(size 0.1397 0.1397)
			(layers "F.Cu" "F.Mask" "F.Paste")
			(net "U54_A1")
			(options
				(clearance outline)
				(anchor circle)
			)
			(primitives
				(gr_poly
					(pts
						(arc
							(start -0.1778 -0.2794)
							(mid -0.249642 -0.249642)
							(end -0.2794 -0.1778)
						)
						(arc
							(start -0.2794 0.1778)
							(mid -0.249642 0.249642)
							(end -0.1778 0.2794)
						)
						(arc
							(start 0.1778 0.2794)
							(mid 0.249642 0.249642)
							(end 0.2794 0.1778)
						)
						(arc
							(start 0.2794 -0.1778)
							(mid 0.249642 -0.249642)
							(end 0.1778 -0.2794)
						)
					)
					(width 0)
					(fill yes)
				)
			)
		)
	)
)
